(kicad_pcb
	(version 20241229)
	(generator "pcbnew")
	(generator_version "9.0")
	(general
		(thickness 1.599998)
		(legacy_teardrops no)
	)
	(paper "A4")
	(title_block
		(title "Artix - Datacenter Secure Control Module (DC-SCM)")
		(date "2024-11-06")
		(rev "1.1.3")
		(comment 9 "footprint 110 of 544 (U14), pads 1-78 of 484")
	)
	(layers
		(0 "F.Cu" signal)
		(4 "In1.Cu" signal)
		(6 "In2.Cu" signal)
		(8 "In3.Cu" signal)
		(10 "In4.Cu" signal)
		(12 "In5.Cu" signal)
		(14 "In6.Cu" signal)
		(2 "B.Cu" signal)
		(9 "F.Adhes" user "F.Adhesive")
		(11 "B.Adhes" user "B.Adhesive")
		(13 "F.Paste" user)
		(15 "B.Paste" user)
		(5 "F.SilkS" user "F.Silkscreen")
		(7 "B.SilkS" user "B.Silkscreen")
		(1 "F.Mask" user)
		(3 "B.Mask" user)
		(17 "Dwgs.User" user "User.Drawings")
		(19 "Cmts.User" user "User.Comments")
		(21 "Eco1.User" user "User.Eco1")
		(23 "Eco2.User" user "User.Eco2")
		(25 "Edge.Cuts" user)
		(27 "Margin" user)
		(31 "F.CrtYd" user "F.Courtyard")
		(29 "B.CrtYd" user "B.Courtyard")
		(35 "F.Fab" user)
		(33 "B.Fab" user)
	)
	(footprint "antmicro-footprints:BGA-484_23x23mm_Layout22x22_P1mm_FGG484"
		(layer "F.Cu")
		(at 101.275 119.675 90)
		(property "Reference" "U14"
			(at 11.965 9.405 180)
			(layer "F.SilkS")
			(effects
				(font
					(size 0.7 0.7)
					(thickness 0.15)
				)
				(justify left bottom)
			)
		)
		(property "Value" "XC7A100T-FGG484"
			(at 0 13.1 90)
			(layer "F.Fab")
			(effects
				(font
					(size 0.7 0.7)
					(thickness 0.15)
				)
				(justify left bottom)
			)
		)
		(property "Datasheet" "https://docs.xilinx.com/v/u/en-US/ds181_Artix_7_Data_Sheet"
			(at 0 0 90)
			(layer "F.Fab")
			(hide yes)
			(effects
				(font
					(size 1.27 1.27)
					(thickness 0.15)
				)
			)
		)
		(property "Description" "Artix-7 Field Programmable Gate Array IC 210 324-LFBGA, CSPBGA"
			(at 0 0 90)
			(layer "F.Fab")
			(hide yes)
			(effects
				(font
					(size 1.27 1.27)
					(thickness 0.15)
				)
			)
		)
		(property "Author" "Antmicro"
			(at 220.95 18.4 0)
			(layer "F.Fab")
			(hide yes)
			(effects
				(font
					(size 1 1)
					(thickness 0.15)
				)
			)
		)
		(property "License" "Apache-2.0"
			(at 220.95 18.4 0)
			(layer "F.Fab")
			(hide yes)
			(effects
				(font
					(size 1 1)
					(thickness 0.15)
				)
			)
		)
		(property "MPN" "XC7A100T-FGG484"
			(at 220.95 18.4 0)
			(layer "F.Fab")
			(hide yes)
			(effects
				(font
					(size 1 1)
					(thickness 0.15)
				)
			)
		)
		(property "Manufacturer" "AMD-Xilinx"
			(at 220.95 18.4 0)
			(layer "F.Fab")
			(hide yes)
			(effects
				(font
					(size 1 1)
					(thickness 0.15)
				)
			)
		)
		(sheetname "/FPGA power supply/")
		(sheetfile "fpga-power-supply.kicad_sch")
		(solder_mask_margin 0.05)
		(attr smd)
		(pad "A1" smd circle
			(at -10.5 -10.5 90)
			(size 0.5 0.5)
			(layers "F.Cu" "F.Mask" "F.Paste")
			(net 178 "DDR3_DQ13")
			(pinfunction "IO_L1N_T0_AD4N_35")
			(pintype "bidirectional")
		)
		(pad "A2" smd circle
			(at -9.5 -10.5 90)
			(size 0.5 0.5)
			(layers "F.Cu" "F.Mask" "F.Paste")
			(net 1 "GND")
			(pinfunction "GND")
			(pintype "power_in")
		)
		(pad "A3" smd circle
			(at -8.5 -10.5 90)
			(size 0.5 0.5)
			(layers "F.Cu" "F.Mask" "F.Paste")
			(net 1 "GND")
			(pinfunction "GND")
			(pintype "passive")
		)
		(pad "A4" smd circle
			(at -7.5 -10.5 90)
			(size 0.5 0.5)
			(layers "F.Cu" "F.Mask" "F.Paste")
			(net 489 "/Interfaces/PCIE_BMC_TX_C_N")
			(pinfunction "MGTPTXN0_216")
			(pintype "bidirectional")
		)
		(pad "A5" smd circle
			(at -6.5 -10.5 90)
			(size 0.5 0.5)
			(layers "F.Cu" "F.Mask" "F.Paste")
			(net 1 "GND")
			(pinfunction "GND")
			(pintype "passive")
		)
		(pad "A6" smd circle
			(at -5.5 -10.5 90)
			(size 0.5 0.5)
			(layers "F.Cu" "F.Mask" "F.Paste")
			(net 535 "unconnected-(U14E-MGTPTXN2_216-PadA6)")
			(pinfunction "MGTPTXN2_216")
			(pintype "bidirectional+no_connect")
		)
		(pad "A7" smd circle
			(at -4.5 -10.5 90)
			(size 0.5 0.5)
			(layers "F.Cu" "F.Mask" "F.Paste")
			(net 1 "GND")
			(pinfunction "GND")
			(pintype "passive")
		)
		(pad "A8" smd circle
			(at -3.5 -10.5 90)
			(size 0.5 0.5)
			(layers "F.Cu" "F.Mask" "F.Paste")
			(net 382 "PCIE_BMC_RX_N")
			(pinfunction "MGTPRXN0_216")
			(pintype "bidirectional")
		)
		(pad "A9" smd circle
			(at -2.5 -10.5 90)
			(size 0.5 0.5)
			(layers "F.Cu" "F.Mask" "F.Paste")
			(net 1 "GND")
			(pinfunction "GND")
			(pintype "passive")
		)
		(pad "A10" smd circle
			(at -1.5 -10.5 90)
			(size 0.5 0.5)
			(layers "F.Cu" "F.Mask" "F.Paste")
			(net 536 "unconnected-(U14E-MGTPRXN2_216-PadA10)")
			(pinfunction "MGTPRXN2_216")
			(pintype "bidirectional+no_connect")
		)
		(pad "A11" smd circle
			(at -0.5 -10.5 90)
			(size 0.5 0.5)
			(layers "F.Cu" "F.Mask" "F.Paste")
			(net 1 "GND")
			(pinfunction "GND")
			(pintype "passive")
		)
		(pad "A12" smd circle
			(at 0.498 -10.5 90)
			(size 0.5 0.5)
			(layers "F.Cu" "F.Mask" "F.Paste")
			(net 1 "GND")
			(pinfunction "GND")
			(pintype "passive")
		)
		(pad "A13" smd circle
			(at 1.499 -10.5 90)
			(size 0.5 0.5)
			(layers "F.Cu" "F.Mask" "F.Paste")
			(net 78 "NCSI_TXEN")
			(pinfunction "IO_L10P_T1_16")
			(pintype "bidirectional")
		)
		(pad "A14" smd circle
			(at 2.499 -10.5 90)
			(size 0.5 0.5)
			(layers "F.Cu" "F.Mask" "F.Paste")
			(net 77 "NCSI_CRS_DV")
			(pinfunction "IO_L10N_T1_16")
			(pintype "bidirectional")
		)
		(pad "A15" smd circle
			(at 3.499 -10.5 90)
			(size 0.5 0.5)
			(layers "F.Cu" "F.Mask" "F.Paste")
			(net 82 "NCSI_RXD0")
			(pinfunction "IO_L9P_T1_DQS_16")
			(pintype "bidirectional")
		)
		(pad "A16" smd circle
			(at 4.498 -10.5 90)
			(size 0.5 0.5)
			(layers "F.Cu" "F.Mask" "F.Paste")
			(net 523 "SPI0_MOSI_R")
			(pinfunction "IO_L9N_T1_DQS_16")
			(pintype "bidirectional")
		)
		(pad "A17" smd circle
			(at 5.499 -10.5 90)
			(size 0.5 0.5)
			(layers "F.Cu" "F.Mask" "F.Paste")
			(net 2 "VCC3V3")
			(pinfunction "VCCO_16")
			(pintype "power_in")
		)
		(pad "A18" smd circle
			(at 6.499 -10.5 90)
			(size 0.5 0.5)
			(layers "F.Cu" "F.Mask" "F.Paste")
			(net 564 "ROT_SCLK")
			(pinfunction "IO_L17P_T2_16")
			(pintype "bidirectional")
		)
		(pad "A19" smd circle
			(at 7.499 -10.5 90)
			(size 0.5 0.5)
			(layers "F.Cu" "F.Mask" "F.Paste")
			(net 563 "ROT_RX")
			(pinfunction "IO_L17N_T2_16")
			(pintype "bidirectional")
		)
		(pad "A20" smd circle
			(at 8.499 -10.5 90)
			(size 0.5 0.5)
			(layers "F.Cu" "F.Mask" "F.Paste")
			(net 562 "ROT_TX")
			(pinfunction "IO_L16N_T2_16")
			(pintype "bidirectional")
		)
		(pad "A21" smd circle
			(at 9.499 -10.5 90)
			(size 0.5 0.5)
			(layers "F.Cu" "F.Mask" "F.Paste")
			(net 169 "I3C[0]_SCL_3V3")
			(pinfunction "IO_L21N_T3_DQS_16")
			(pintype "bidirectional")
		)
		(pad "A22" smd circle
			(at 10.499 -10.5 90)
			(size 0.5 0.5)
			(layers "F.Cu" "F.Mask" "F.Paste")
			(net 1 "GND")
			(pinfunction "GND")
			(pintype "passive")
		)
		(pad "AA1" smd circle
			(at -10.5 9.499 90)
			(size 0.5 0.5)
			(layers "F.Cu" "F.Mask" "F.Paste")
			(net 397 "SPARE0_R")
			(pinfunction "IO_L7P_T1_34")
			(pintype "bidirectional")
		)
		(pad "AA2" smd circle
			(at -9.5 9.499 90)
			(size 0.5 0.5)
			(layers "F.Cu" "F.Mask" "F.Paste")
			(net 1 "GND")
			(pinfunction "GND")
			(pintype "passive")
		)
		(pad "AA3" smd circle
			(at -8.5 9.499 90)
			(size 0.5 0.5)
			(layers "F.Cu" "F.Mask" "F.Paste")
			(net 468 "ULPI2_DATA1")
			(pinfunction "IO_L9N_T1_DQS_34")
			(pintype "bidirectional")
		)
		(pad "AA4" smd circle
			(at -7.5 9.499 90)
			(size 0.5 0.5)
			(layers "F.Cu" "F.Mask" "F.Paste")
			(net 465 "ULPI2_DATA4")
			(pinfunction "IO_L11N_T1_SRCC_34")
			(pintype "bidirectional")
		)
		(pad "AA5" smd circle
			(at -6.5 9.499 90)
			(size 0.5 0.5)
			(layers "F.Cu" "F.Mask" "F.Paste")
			(net 463 "ULPI2_DATA6")
			(pinfunction "IO_L10P_T1_34")
			(pintype "bidirectional")
		)
		(pad "AA6" smd circle
			(at -5.5 9.499 90)
			(size 0.5 0.5)
			(layers "F.Cu" "F.Mask" "F.Paste")
			(net 460 "ULPI2_STP")
			(pinfunction "IO_L18N_T2_34")
			(pintype "bidirectional")
		)
		(pad "AA7" smd circle
			(at -4.5 9.499 90)
			(size 0.5 0.5)
			(layers "F.Cu" "F.Mask" "F.Paste")
			(net 2 "VCC3V3")
			(pinfunction "VCCO_34")
			(pintype "passive")
		)
		(pad "AA8" smd circle
			(at -3.5 9.499 90)
			(size 0.5 0.5)
			(layers "F.Cu" "F.Mask" "F.Paste")
			(net 457 "ULPI2_RESET")
			(pinfunction "IO_L22P_T3_34")
			(pintype "bidirectional")
		)
		(pad "AA9" smd circle
			(at -2.5 9.499 90)
			(size 0.5 0.5)
			(layers "F.Cu" "F.Mask" "F.Paste")
			(net 537 "unconnected-(U14A-IO_L8P_T1_13-PadAA9)")
			(pinfunction "IO_L8P_T1_13")
			(pintype "bidirectional+no_connect")
		)
		(pad "AA10" smd circle
			(at -1.5 9.499 90)
			(size 0.5 0.5)
			(layers "F.Cu" "F.Mask" "F.Paste")
			(net 539 "unconnected-(U14A-IO_L9P_T1_DQS_13-PadAA10)")
			(pinfunction "IO_L9P_T1_DQS_13")
			(pintype "bidirectional+no_connect")
		)
		(pad "AA11" smd circle
			(at -0.5 9.499 90)
			(size 0.5 0.5)
			(layers "F.Cu" "F.Mask" "F.Paste")
			(net 540 "unconnected-(U14A-IO_L9N_T1_DQS_13-PadAA11)")
			(pinfunction "IO_L9N_T1_DQS_13")
			(pintype "bidirectional+no_connect")
		)
		(pad "AA12" smd circle
			(at 0.498 9.499 90)
			(size 0.5 0.5)
			(layers "F.Cu" "F.Mask" "F.Paste")
			(net 1 "GND")
			(pinfunction "GND")
			(pintype "passive")
		)
		(pad "AA13" smd circle
			(at 1.499 9.499 90)
			(size 0.5 0.5)
			(layers "F.Cu" "F.Mask" "F.Paste")
			(net 541 "unconnected-(U14A-IO_L3P_T0_DQS_13-PadAA13)")
			(pinfunction "IO_L3P_T0_DQS_13")
			(pintype "bidirectional+no_connect")
		)
		(pad "AA14" smd circle
			(at 2.499 9.499 90)
			(size 0.5 0.5)
			(layers "F.Cu" "F.Mask" "F.Paste")
			(net 542 "unconnected-(U14A-IO_L5N_T0_13-PadAA14)")
			(pinfunction "IO_L5N_T0_13")
			(pintype "bidirectional+no_connect")
		)
		(pad "AA15" smd circle
			(at 3.499 9.499 90)
			(size 0.5 0.5)
			(layers "F.Cu" "F.Mask" "F.Paste")
			(net 543 "unconnected-(U14A-IO_L4P_T0_13-PadAA15)")
			(pinfunction "IO_L4P_T0_13")
			(pintype "bidirectional+no_connect")
		)
		(pad "AA16" smd circle
			(at 4.498 9.499 90)
			(size 0.5 0.5)
			(layers "F.Cu" "F.Mask" "F.Paste")
			(net 544 "unconnected-(U14A-IO_L1N_T0_13-PadAA16)")
			(pinfunction "IO_L1N_T0_13")
			(pintype "bidirectional+no_connect")
		)
		(pad "AA17" smd circle
			(at 5.499 9.499 90)
			(size 0.5 0.5)
			(layers "F.Cu" "F.Mask" "F.Paste")
			(net 2 "VCC3V3")
			(pinfunction "VCCO_13")
			(pintype "passive")
		)
		(pad "AA18" smd circle
			(at 6.499 9.499 90)
			(size 0.5 0.5)
			(layers "F.Cu" "F.Mask" "F.Paste")
			(net 454 "ULPI1_DATA1")
			(pinfunction "IO_L17P_T2_A14_D30_14")
			(pintype "bidirectional")
		)
		(pad "AA19" smd circle
			(at 7.499 9.499 90)
			(size 0.5 0.5)
			(layers "F.Cu" "F.Mask" "F.Paste")
			(net 453 "ULPI1_DATA2")
			(pinfunction "IO_L15P_T2_DQS_RDWR_B_14")
			(pintype "bidirectional")
		)
		(pad "AA20" smd circle
			(at 8.499 9.499 90)
			(size 0.5 0.5)
			(layers "F.Cu" "F.Mask" "F.Paste")
			(net 451 "ULPI1_DATA4")
			(pinfunction "IO_L8P_T1_D11_14")
			(pintype "bidirectional")
		)
		(pad "AA21" smd circle
			(at 9.499 9.499 90)
			(size 0.5 0.5)
			(layers "F.Cu" "F.Mask" "F.Paste")
			(net 449 "ULPI1_DATA6")
			(pinfunction "IO_L8N_T1_D12_14")
			(pintype "bidirectional")
		)
		(pad "AA22" smd circle
			(at 10.499 9.499 90)
			(size 0.5 0.5)
			(layers "F.Cu" "F.Mask" "F.Paste")
			(net 1 "GND")
			(pinfunction "GND")
			(pintype "passive")
		)
		(pad "AB1" smd circle
			(at -10.5 10.499 90)
			(size 0.5 0.5)
			(layers "F.Cu" "F.Mask" "F.Paste")
			(net 398 "IRQ_N_R")
			(pinfunction "IO_L7N_T1_34")
			(pintype "bidirectional")
		)
		(pad "AB2" smd circle
			(at -9.5 10.499 90)
			(size 0.5 0.5)
			(layers "F.Cu" "F.Mask" "F.Paste")
			(net 469 "ULPI2_DATA0")
			(pinfunction "IO_L8N_T1_34")
			(pintype "bidirectional")
		)
		(pad "AB3" smd circle
			(at -8.5 10.499 90)
			(size 0.5 0.5)
			(layers "F.Cu" "F.Mask" "F.Paste")
			(net 467 "ULPI2_DATA2")
			(pinfunction "IO_L8P_T1_34")
			(pintype "bidirectional")
		)
		(pad "AB4" smd circle
			(at -7.5 10.499 90)
			(size 0.5 0.5)
			(layers "F.Cu" "F.Mask" "F.Paste")
			(net 2 "VCC3V3")
			(pinfunction "VCCO_34")
			(pintype "passive")
		)
		(pad "AB5" smd circle
			(at -6.5 10.499 90)
			(size 0.5 0.5)
			(layers "F.Cu" "F.Mask" "F.Paste")
			(net 464 "ULPI2_DATA5")
			(pinfunction "IO_L10N_T1_34")
			(pintype "bidirectional")
		)
		(pad "AB6" smd circle
			(at -5.5 10.499 90)
			(size 0.5 0.5)
			(layers "F.Cu" "F.Mask" "F.Paste")
			(net 462 "ULPI2_DATA7")
			(pinfunction "IO_L20N_T3_34")
			(pintype "bidirectional")
		)
		(pad "AB7" smd circle
			(at -4.5 10.499 90)
			(size 0.5 0.5)
			(layers "F.Cu" "F.Mask" "F.Paste")
			(net 459 "ULPI2_DIR")
			(pinfunction "IO_L20P_T3_34")
			(pintype "bidirectional")
		)
		(pad "AB8" smd circle
			(at -3.5 10.499 90)
			(size 0.5 0.5)
			(layers "F.Cu" "F.Mask" "F.Paste")
			(net 458 "ULPI2_NXT")
			(pinfunction "IO_L22N_T3_34")
			(pintype "bidirectional")
		)
		(pad "AB9" smd circle
			(at -2.5 10.499 90)
			(size 0.5 0.5)
			(layers "F.Cu" "F.Mask" "F.Paste")
			(net 1 "GND")
			(pinfunction "GND")
			(pintype "passive")
		)
		(pad "AB10" smd circle
			(at -1.5 10.499 90)
			(size 0.5 0.5)
			(layers "F.Cu" "F.Mask" "F.Paste")
			(net 545 "unconnected-(U14A-IO_L8N_T1_13-PadAB10)")
			(pinfunction "IO_L8N_T1_13")
			(pintype "bidirectional+no_connect")
		)
		(pad "AB11" smd circle
			(at -0.5 10.499 90)
			(size 0.5 0.5)
			(layers "F.Cu" "F.Mask" "F.Paste")
			(net 546 "unconnected-(U14A-IO_L7P_T1_13-PadAB11)")
			(pinfunction "IO_L7P_T1_13")
			(pintype "bidirectional+no_connect")
		)
		(pad "AB12" smd circle
			(at 0.498 10.499 90)
			(size 0.5 0.5)
			(layers "F.Cu" "F.Mask" "F.Paste")
			(net 547 "unconnected-(U14A-IO_L7N_T1_13-PadAB12)")
			(pinfunction "IO_L7N_T1_13")
			(pintype "bidirectional+no_connect")
		)
		(pad "AB13" smd circle
			(at 1.499 10.499 90)
			(size 0.5 0.5)
			(layers "F.Cu" "F.Mask" "F.Paste")
			(net 548 "unconnected-(U14A-IO_L3N_T0_DQS_13-PadAB13)")
			(pinfunction "IO_L3N_T0_DQS_13")
			(pintype "bidirectional+no_connect")
		)
		(pad "AB14" smd circle
			(at 2.499 10.499 90)
			(size 0.5 0.5)
			(layers "F.Cu" "F.Mask" "F.Paste")
			(net 2 "VCC3V3")
			(pinfunction "VCCO_13")
			(pintype "passive")
		)
		(pad "AB15" smd circle
			(at 3.499 10.499 90)
			(size 0.5 0.5)
			(layers "F.Cu" "F.Mask" "F.Paste")
			(net 549 "unconnected-(U14A-IO_L4N_T0_13-PadAB15)")
			(pinfunction "IO_L4N_T0_13")
			(pintype "bidirectional+no_connect")
		)
		(pad "AB16" smd circle
			(at 4.498 10.499 90)
			(size 0.5 0.5)
			(layers "F.Cu" "F.Mask" "F.Paste")
			(net 550 "unconnected-(U14A-IO_L2P_T0_13-PadAB16)")
			(pinfunction "IO_L2P_T0_13")
			(pintype "bidirectional+no_connect")
		)
		(pad "AB17" smd circle
			(at 5.499 10.499 90)
			(size 0.5 0.5)
			(layers "F.Cu" "F.Mask" "F.Paste")
			(net 551 "unconnected-(U14A-IO_L2N_T0_13-PadAB17)")
			(pinfunction "IO_L2N_T0_13")
			(pintype "bidirectional+no_connect")
		)
		(pad "AB18" smd circle
			(at 6.499 10.499 90)
			(size 0.5 0.5)
			(layers "F.Cu" "F.Mask" "F.Paste")
			(net 455 "ULPI1_DATA0")
			(pinfunction "IO_L17N_T2_A13_D29_14")
			(pintype "bidirectional")
		)
		(pad "AB19" smd circle
			(at 7.499 10.499 90)
			(size 0.5 0.5)
			(layers "F.Cu" "F.Mask" "F.Paste")
			(net 1 "GND")
			(pinfunction "GND")
			(pintype "passive")
		)
		(pad "AB20" smd circle
			(at 8.499 10.499 90)
			(size 0.5 0.5)
			(layers "F.Cu" "F.Mask" "F.Paste")
			(net 452 "ULPI1_DATA3")
			(pinfunction "IO_L15N_T2_DQS_DOUT_CSO_B_14")
			(pintype "bidirectional")
		)
		(pad "AB21" smd circle
			(at 9.499 10.499 90)
			(size 0.5 0.5)
			(layers "F.Cu" "F.Mask" "F.Paste")
			(net 450 "ULPI1_DATA5")
			(pinfunction "IO_L10P_T1_D14_14")
			(pintype "bidirectional")
		)
		(pad "AB22" smd circle
			(at 10.499 10.499 90)
			(size 0.5 0.5)
			(layers "F.Cu" "F.Mask" "F.Paste")
			(net 448 "ULPI1_DATA7")
			(pinfunction "IO_L10N_T1_D15_14")
			(pintype "bidirectional")
		)
		(pad "B1" smd circle
			(at -10.5 -9.5 90)
			(size 0.5 0.5)
			(layers "F.Cu" "F.Mask" "F.Paste")
			(net 177 "DDR3_DQ15")
			(pinfunction "IO_L1P_T0_AD4P_35")
			(pintype "bidirectional")
		)
		(pad "B2" smd circle
			(at -9.5 -9.5 90)
			(size 0.5 0.5)
			(layers "F.Cu" "F.Mask" "F.Paste")
			(net 180 "DDR3_DQ9")
			(pinfunction "IO_L2N_T0_AD12N_35")
			(pintype "bidirectional")
		)
		(pad "B3" smd circle
			(at -8.5 -9.5 90)
			(size 0.5 0.5)
			(layers "F.Cu" "F.Mask" "F.Paste")
			(net 1 "GND")
			(pinfunction "GND")
			(pintype "passive")
		)
		(pad "B4" smd circle
			(at -7.5 -9.5 90)
			(size 0.5 0.5)
			(layers "F.Cu" "F.Mask" "F.Paste")
			(net 490 "/Interfaces/PCIE_BMC_TX_C_P")
			(pinfunction "MGTPTXP0_216")
			(pintype "bidirectional")
		)
		(pad "B5" smd circle
			(at -6.5 -9.5 90)
			(size 0.5 0.5)
			(layers "F.Cu" "F.Mask" "F.Paste")
			(net 339 "VCC1V2")
			(pinfunction "MGTAVTT")
			(pintype "power_in")
		)
		(pad "B6" smd circle
			(at -5.5 -9.5 90)
			(size 0.5 0.5)
			(layers "F.Cu" "F.Mask" "F.Paste")
			(net 552 "unconnected-(U14E-MGTPTXP2_216-PadB6)")
			(pinfunction "MGTPTXP2_216")
			(pintype "bidirectional+no_connect")
		)
		(pad "B7" smd circle
			(at -4.5 -9.5 90)
			(size 0.5 0.5)
			(layers "F.Cu" "F.Mask" "F.Paste")
			(net 339 "VCC1V2")
			(pinfunction "MGTAVTT")
			(pintype "passive")
		)
		(pad "B8" smd circle
			(at -3.5 -9.5 90)
			(size 0.5 0.5)
			(layers "F.Cu" "F.Mask" "F.Paste")
			(net 381 "PCIE_BMC_RX_P")
			(pinfunction "MGTPRXP0_216")
			(pintype "bidirectional")
		)
		(pad "B9" smd circle
			(at -2.5 -9.5 90)
			(size 0.5 0.5)
			(layers "F.Cu" "F.Mask" "F.Paste")
			(net 339 "VCC1V2")
			(pinfunction "MGTAVTT")
			(pintype "passive")
		)
		(pad "B10" smd circle
			(at -1.5 -9.5 90)
			(size 0.5 0.5)
			(layers "F.Cu" "F.Mask" "F.Paste")
			(net 553 "unconnected-(U14E-MGTPRXP2_216-PadB10)")
			(pinfunction "MGTPRXP2_216")
			(pintype "bidirectional+no_connect")
		)
		(pad "B11" smd circle
			(at -0.5 -9.5 90)
			(size 0.5 0.5)
			(layers "F.Cu" "F.Mask" "F.Paste")
			(net 339 "VCC1V2")
			(pinfunction "MGTAVTT")
			(pintype "passive")
		)
		(pad "B12" smd circle
			(at 0.498 -9.5 90)
			(size 0.5 0.5)
			(layers "F.Cu" "F.Mask" "F.Paste")
			(net 1 "GND")
			(pinfunction "GND")
			(pintype "passive")
		)
	)
)
